# BASEBOARD_FAB2 (Tioga Pass) — schematic netlist excerpt (pin names and nets, part order shuffled) for the footprints in the layout excerpt that follows; sources: Cadence DE-HDL packaged netlist, KiCad conversion of Wiwynn_Tioga_Pass_MB.brd

EU7E2  TPS54821  IC  pkg LCC  page 241
  RT_CLK  = VR_P5V_STBY_RT
  GND(0)  = GND
  GND(1)  = GND
  PVIN(0)  = VR_FET_SW_P5V_STBY_PVIN
  PVIN(1)  = VR_FET_SW_P5V_STBY_PVIN
  VIN  = VR_P5V_STBY_VIN
  VSENSE  = VR_P5V_STBY_VSENSE
  COMP  = VR_P5V_STBY_COMP
  SS_TR  = VR_P5V_STBY_SS
  EN  = VR_P5V_STBY_EN
  PH(0)  = VR_P5V_STBY_PHASE
  PH(1)  = VR_P5V_STBY_PHASE
  BOOT  = VR_P5V_STBY_BOOT
  PWRGD  = PWRGD_P5V_STBY_R
  THPAD  = GND

(kicad_pcb
	(version 20260206)
	(generator "pcbnew")
	(generator_version "10.0")
	(general
		(thickness 1.6)
		(legacy_teardrops no)
	)
	(paper "A4")
	(title_block
		(title "Wiwynn_Tioga_Pass_MB.brd")
		(comment 1 "Tioga Pass / footprints 718-718 of 4770")
	)
	(layers
		(0 "F.Cu" signal "TOP")
		(4 "In1.Cu" signal "L2GND")
		(6 "In2.Cu" signal "L3")
		(8 "In3.Cu" signal "L4GND")
		(10 "In4.Cu" signal "L5")
		(12 "In5.Cu" signal "L6GND")
		(14 "In6.Cu" signal "L7VCC")
		(16 "In7.Cu" signal "L8VCC")
		(18 "In8.Cu" signal "L9GND")
		(20 "In9.Cu" signal "L10")
		(22 "In10.Cu" signal "L11GND")
		(24 "In11.Cu" signal "L12")
		(26 "In12.Cu" signal "L13GND")
		(2 "B.Cu" signal "BOTTOM")
		(9 "F.Adhes" user "F.Adhesive")
		(11 "B.Adhes" user "B.Adhesive")
		(13 "F.Paste" user "Package Geometry/Pastemask Top")
		(15 "B.Paste" user "Package Geometry/Pastemask Bottom")
		(5 "F.SilkS" user "Ref Des/Silkscreen Top")
		(7 "B.SilkS" user "Ref Des/Silkscreen Bottom")
		(1 "F.Mask" user "Board Geometry/Soldermask Top")
		(3 "B.Mask" user "Board Geometry/Soldermask Bottom")
		(17 "Dwgs.User" user "User.Drawings")
		(19 "Cmts.User" user "User.Comments")
		(21 "Eco1.User" user "User.Eco1")
		(23 "Eco2.User" user "User.Eco2")
		(25 "Edge.Cuts" user "Board Geometry/Outline")
		(27 "Margin" user)
		(31 "F.CrtYd" user "Package Geometry/Place Bound Top")
		(29 "B.CrtYd" user "Package Geometry/Place Bound Bottom")
		(35 "F.Fab" user "Ref Des/Assembly Top")
		(33 "B.Fab" user "Ref Des/Assembly Bottom")
	)
	(footprint ""
		(layer "F.Cu")
		(at 392.176 -67.691)
		(property "Reference" "EU7E2"
			(at 2.90195 0.67056 90)
			(unlocked yes)
			(layer "F.SilkS")
			(effects
				(font
					(size 0.7874 0.5842)
					(thickness 0.1524)
				)
				(justify left)
			)
		)
		(property "Value" ""
			(at 0 0 0)
			(layer "F.Fab")
			(effects
				(font
					(size 1.27 1.27)
				)
			)
		)
		(duplicate_pad_numbers_are_jumpers no)
		(fp_line
			(start -1.82499 -1.82499)
			(end -1.82499 -1.571498)
			(stroke
				(width 0.1524)
				(type default)
			)
			(layer "F.SilkS")
		)
		(fp_line
			(start -1.82499 1.571498)
			(end -1.82499 1.82499)
			(stroke
				(width 0.1524)
				(type default)
			)
			(layer "F.SilkS")
		)
		(fp_line
			(start -1.82499 1.82499)
			(end -1.321562 1.82499)
			(stroke
				(width 0.1524)
				(type default)
			)
			(layer "F.SilkS")
		)
		(fp_line
			(start -1.321562 -1.82499)
			(end -1.82499 -1.82499)
			(stroke
				(width 0.1524)
				(type default)
			)
			(layer "F.SilkS")
		)
		(fp_line
			(start 1.321562 1.82499)
			(end 1.82499 1.82499)
			(stroke
				(width 0.1524)
				(type default)
			)
			(layer "F.SilkS")
		)
		(fp_line
			(start 1.82499 -1.82499)
			(end 1.321562 -1.82499)
			(stroke
				(width 0.1524)
				(type default)
			)
			(layer "F.SilkS")
		)
		(fp_line
			(start 1.82499 -1.571498)
			(end 1.82499 -1.82499)
			(stroke
				(width 0.1524)
				(type default)
			)
			(layer "F.SilkS")
		)
		(fp_line
			(start 1.82499 1.82499)
			(end 1.82499 1.571498)
			(stroke
				(width 0.1524)
				(type default)
			)
			(layer "F.SilkS")
		)
		(fp_circle
			(center -1.287272 -2.56667)
			(end -1.160272 -2.56667)
			(stroke
				(width 0.254)
				(type default)
			)
			(fill no)
			(layer "F.SilkS")
		)
		(fp_poly
			(pts
				(xy -2.09169 -2.09169) (xy -2.09169 -1.32969) (xy -1.32969 -2.09169)
			)
			(stroke
				(width 0)
				(type default)
			)
			(fill yes)
			(layer "F.SilkS")
		)
		(fp_poly
			(pts
				(xy -1.0287 1.0287) (xy -1.0287 -1.0287) (xy -0.381 -1.0287) (xy -0.381 -2.1336) (xy -0.1905 -2.1336)
				(xy -0.1905 -1.397) (xy 0.1905 -1.397) (xy 0.1905 -2.1336) (xy 0.381 -2.1336) (xy 0.381 -1.0287)
				(xy 1.0287 -1.0287) (xy 1.0287 1.0287) (xy 0.381 1.0287) (xy 0.381 2.1336) (xy 0.1905 2.1336) (xy 0.1905 1.397)
				(xy -0.1905 1.397) (xy -0.1905 2.1336) (xy -0.381 2.1336) (xy -0.381 1.0287)
			)
			(stroke
				(width 0)
				(type default)
			)
			(fill yes)
			(layer "F.Paste")
		)
		(fp_rect
			(start -1.82499 1.82499)
			(end 1.82499 -1.82499)
			(stroke
				(width 0)
				(type default)
			)
			(fill no)
			(layer "F.CrtYd")
		)
		(fp_line
			(start -1.82499 -1.82499)
			(end 1.82499 -1.82499)
			(stroke
				(width 0.1)
				(type default)
			)
			(layer "F.Fab")
		)
		(fp_line
			(start -1.82499 1.82499)
			(end -1.82499 -1.82499)
			(stroke
				(width 0.1)
				(type default)
			)
			(layer "F.Fab")
		)
		(fp_line
			(start 1.82499 -1.82499)
			(end 1.82499 1.82499)
			(stroke
				(width 0.1)
				(type default)
			)
			(layer "F.Fab")
		)
		(fp_line
			(start 1.82499 1.82499)
			(end -1.82499 1.82499)
			(stroke
				(width 0.1)
				(type default)
			)
			(layer "F.Fab")
		)
		(fp_circle
			(center -1.287272 -2.56667)
			(end -1.160272 -2.56667)
			(stroke
				(width 0.254)
				(type default)
			)
			(fill no)
			(layer "F.Fab")
		)
		(pad "1" smd rect
			(at -0.750062 -1.7145)
			(size 0.2794 0.8382)
			(layers "F.Cu" "F.Mask" "F.Paste")
			(net "VR_P5V_STBY_RT")
		)
		(pad "2" smd rect
			(at -1.7145 -0.999998)
			(size 0.8382 0.2794)
			(layers "F.Cu" "F.Mask" "F.Paste")
			(net "GND")
		)
		(pad "3" smd rect
			(at -1.7145 -0.500126)
			(size 0.8382 0.2794)
			(layers "F.Cu" "F.Mask" "F.Paste")
			(net "GND")
		)
		(pad "4" smd rect
			(at -1.7145 0)
			(size 0.8382 0.2794)
			(layers "F.Cu" "F.Mask" "F.Paste")
			(net "VR_FET_SW_P5V_STBY_PVIN")
		)
		(pad "5" smd rect
			(at -1.7145 0.500126)
			(size 0.8382 0.2794)
			(layers "F.Cu" "F.Mask" "F.Paste")
			(net "VR_FET_SW_P5V_STBY_PVIN")
		)
		(pad "6" smd rect
			(at -1.7145 0.999998)
			(size 0.8382 0.2794)
			(layers "F.Cu" "F.Mask" "F.Paste")
			(net "VR_P5V_STBY_VIN")
		)
		(pad "7" smd rect
			(at -0.750062 1.7145)
			(size 0.2794 0.8382)
			(layers "F.Cu" "F.Mask" "F.Paste")
			(net "VR_P5V_STBY_VSENSE")
		)
		(pad "8" smd rect
			(at 0.750062 1.7145)
			(size 0.2794 0.8382)
			(layers "F.Cu" "F.Mask" "F.Paste")
			(net "VR_P5V_STBY_COMP")
		)
		(pad "9" smd rect
			(at 1.7145 0.999998)
			(size 0.8382 0.2794)
			(layers "F.Cu" "F.Mask" "F.Paste")
			(net "VR_P5V_STBY_SS")
		)
		(pad "10" smd rect
			(at 1.7145 0.500126)
			(size 0.8382 0.2794)
			(layers "F.Cu" "F.Mask" "F.Paste")
			(net "VR_P5V_STBY_EN")
		)
		(pad "11" smd rect
			(at 1.7145 0)
			(size 0.8382 0.2794)
			(layers "F.Cu" "F.Mask" "F.Paste")
			(net "VR_P5V_STBY_PHASE")
		)
		(pad "12" smd rect
			(at 1.7145 -0.500126)
			(size 0.8382 0.2794)
			(layers "F.Cu" "F.Mask" "F.Paste")
			(net "VR_P5V_STBY_PHASE")
		)
		(pad "13" smd rect
			(at 1.7145 -0.999998)
			(size 0.8382 0.2794)
			(layers "F.Cu" "F.Mask" "F.Paste")
			(net "VR_P5V_STBY_BOOT")
		)
		(pad "14" smd rect
			(at 0.750062 -1.7145)
			(size 0.2794 0.8382)
			(layers "F.Cu" "F.Mask" "F.Paste")
			(net "PWRGD_P5V_STBY_R")
		)
		(pad "15" smd custom
			(at 0 0)
			(size 0.51435 0.51435)
			(layers "F.Cu" "F.Mask" "F.Paste")
			(net "GND")
			(options
				(clearance outline)
				(anchor circle)
			)
			(primitives
				(gr_poly
					(pts
						(xy -0.381 -2.1336) (xy -0.381 -1.0287) (xy -1.0287 -1.0287) (xy -1.0287 1.0287) (xy -0.381 1.0287)
						(xy -0.381 2.1336) (xy -0.1905 2.1336) (xy -0.1905 1.397) (xy 0.1905 1.397) (xy 0.1905 2.1336)
						(xy 0.381 2.1336) (xy 0.381 1.0287) (xy 1.0287 1.0287) (xy 1.0287 -1.0287) (xy 0.381 -1.0287)
						(xy 0.381 -2.1336) (xy 0.1905 -2.1336) (xy 0.1905 -1.397) (xy -0.1905 -1.397) (xy -0.1905 -2.1336)
					)
					(width 0)
					(fill yes)
				)
			)
		)
	)
)
